# BASEBOARD_FAB2 (Tioga Pass) — schematic netlist excerpt (pin names and nets, part order shuffled) for the footprints in the layout excerpt that follows; sources: Cadence DE-HDL packaged netlist, KiCad conversion of Wiwynn_Tioga_Pass_MB.brd

R9F20  RES  348 1% EMPTY  pkg 0402  page 145 : A = PECI_BMC ; B = GND
R7A17  RES  150.0 1% CHIP  pkg 0402  page 218 : A = SVID_CLK1_CPU0_R ; B = SVID_CLK_PVDDQ_DEF
C4D16  CAP  1.0UF 16V 10% X6S  pkg 0402  page 203 : A = VR_PVCCIN_CPU0_PH3_VCIN ; B = GND

(kicad_pcb
	(version 20260206)
	(generator "pcbnew")
	(generator_version "10.0")
	(general
		(thickness 1.6)
		(legacy_teardrops no)
	)
	(paper "A4")
	(title_block
		(title "Wiwynn_Tioga_Pass_MB.brd")
		(comment 1 "Tioga Pass / footprints 1103-1105 of 4770")
	)
	(layers
		(0 "F.Cu" signal "TOP")
		(4 "In1.Cu" signal "L2GND")
		(6 "In2.Cu" signal "L3")
		(8 "In3.Cu" signal "L4GND")
		(10 "In4.Cu" signal "L5")
		(12 "In5.Cu" signal "L6GND")
		(14 "In6.Cu" signal "L7VCC")
		(16 "In7.Cu" signal "L8VCC")
		(18 "In8.Cu" signal "L9GND")
		(20 "In9.Cu" signal "L10")
		(22 "In10.Cu" signal "L11GND")
		(24 "In11.Cu" signal "L12")
		(26 "In12.Cu" signal "L13GND")
		(2 "B.Cu" signal "BOTTOM")
		(9 "F.Adhes" user "F.Adhesive")
		(11 "B.Adhes" user "B.Adhesive")
		(13 "F.Paste" user "Package Geometry/Pastemask Top")
		(15 "B.Paste" user "Package Geometry/Pastemask Bottom")
		(5 "F.SilkS" user "Ref Des/Silkscreen Top")
		(7 "B.SilkS" user "Ref Des/Silkscreen Bottom")
		(1 "F.Mask" user "Board Geometry/Soldermask Top")
		(3 "B.Mask" user "Board Geometry/Soldermask Bottom")
		(17 "Dwgs.User" user "User.Drawings")
		(19 "Cmts.User" user "User.Comments")
		(21 "Eco1.User" user "User.Eco1")
		(23 "Eco2.User" user "User.Eco2")
		(25 "Edge.Cuts" user "Board Geometry/Outline")
		(27 "Margin" user)
		(31 "F.CrtYd" user "Package Geometry/Place Bound Top")
		(29 "B.CrtYd" user "Package Geometry/Place Bound Bottom")
		(35 "F.Fab" user "Ref Des/Assembly Top")
		(33 "B.Fab" user "Ref Des/Assembly Bottom")
	)
	(footprint ""
		(layer "F.Cu")
		(at 434.5051 -43.1038)
		(property "Reference" "R9F20"
			(at 0 0 0)
			(layer "F.SilkS")
			(hide yes)
			(effects
				(font
					(size 1.27 1.27)
				)
			)
		)
		(property "Value" ""
			(at 0 0 0)
			(layer "F.Fab")
			(effects
				(font
					(size 1.27 1.27)
				)
			)
		)
		(duplicate_pad_numbers_are_jumpers no)
		(fp_poly
			(pts
				(xy -0.2794 -0.1016) (xy 0.2794 -0.1016) (xy 0.2794 0.9906) (xy -0.2794 0.9906)
			)
			(stroke
				(width 0)
				(type default)
			)
			(fill no)
			(layer "F.CrtYd")
		)
		(fp_line
			(start -0.2794 -0.1016)
			(end -0.2794 0.9906)
			(stroke
				(width 0.1)
				(type default)
			)
			(layer "F.Fab")
		)
		(fp_line
			(start -0.2794 0.9906)
			(end 0.2794 0.9906)
			(stroke
				(width 0.1)
				(type default)
			)
			(layer "F.Fab")
		)
		(fp_line
			(start 0.2794 -0.1016)
			(end -0.2794 -0.1016)
			(stroke
				(width 0.1)
				(type default)
			)
			(layer "F.Fab")
		)
		(fp_line
			(start 0.2794 0.9906)
			(end 0.2794 -0.1016)
			(stroke
				(width 0.1)
				(type default)
			)
			(layer "F.Fab")
		)
		(pad "1" smd rect
			(at 0 0)
			(size 0.508 0.508)
			(layers "F.Cu" "F.Mask" "F.Paste")
			(net "PECI_BMC")
		)
		(pad "2" smd rect
			(at 0 0.889)
			(size 0.508 0.508)
			(layers "F.Cu" "F.Mask" "F.Paste")
			(net "GND")
		)
		(zone
			(layer "F.Cu")
			(hatch none 0.5)
			(connect_pads
				(clearance 0)
			)
			(min_thickness 0.25)
			(keepout
				(tracks allowed)
				(vias not_allowed)
				(pads allowed)
				(copperpour not_allowed)
				(footprints allowed)
			)
			(placement
				(enabled no)
				(sheetname "")
			)
			(fill
				(thermal_gap 0.5)
				(thermal_bridge_width 0.5)
				(island_removal_mode 0)
			)
			(polygon
				(pts
					(xy 434.2511 -42.8498) (xy 434.7591 -42.8498) (xy 434.7591 -42.4688) (xy 434.2511 -42.4688)
				)
			)
		)
		(zone
			(layer "F.Cu")
			(hatch none 0.5)
			(connect_pads
				(clearance 0)
			)
			(min_thickness 0.25)
			(keepout
				(tracks not_allowed)
				(vias allowed)
				(pads allowed)
				(copperpour not_allowed)
				(footprints allowed)
			)
			(placement
				(enabled no)
				(sheetname "")
			)
			(fill
				(thermal_gap 0.5)
				(thermal_bridge_width 0.5)
				(island_removal_mode 0)
			)
			(polygon
				(pts
					(xy 434.2511 -42.4688) (xy 434.7591 -42.4688) (xy 434.7591 -42.8498) (xy 434.2511 -42.8498)
				)
			)
		)
	)
	(footprint ""
		(layer "F.Cu")
		(at 197.108826 -69.324474 -90)
		(property "Reference" "C4D16"
			(at 0 0 270)
			(layer "F.SilkS")
			(hide yes)
			(effects
				(font
					(size 1.27 1.27)
				)
			)
		)
		(property "Value" ""
			(at 0 0 270)
			(layer "F.Fab")
			(effects
				(font
					(size 1.27 1.27)
				)
			)
		)
		(duplicate_pad_numbers_are_jumpers no)
		(fp_poly
			(pts
				(xy 0.3048 -0.1016) (xy 0.3048 0.9906) (xy -0.3048 0.9906) (xy -0.3048 -0.1016)
			)
			(stroke
				(width 0)
				(type default)
			)
			(fill no)
			(layer "F.CrtYd")
		)
		(fp_line
			(start -0.3048 0.9906)
			(end 0.3048 0.9906)
			(stroke
				(width 0.1)
				(type default)
			)
			(layer "F.Fab")
		)
		(fp_line
			(start 0.3048 0.9906)
			(end 0.3048 -0.1016)
			(stroke
				(width 0.1)
				(type default)
			)
			(layer "F.Fab")
		)
		(fp_line
			(start -0.3048 -0.1016)
			(end -0.3048 0.9906)
			(stroke
				(width 0.1)
				(type default)
			)
			(layer "F.Fab")
		)
		(fp_line
			(start 0.3048 -0.1016)
			(end -0.3048 -0.1016)
			(stroke
				(width 0.1)
				(type default)
			)
			(layer "F.Fab")
		)
		(pad "1" smd rect
			(at 0 0 270)
			(size 0.508 0.508)
			(layers "F.Cu" "F.Mask" "F.Paste")
			(net "VR_PVCCIN_CPU0_PH3_VCIN")
		)
		(pad "2" smd rect
			(at 0 0.889 270)
			(size 0.508 0.508)
			(layers "F.Cu" "F.Mask" "F.Paste")
			(net "GND")
		)
		(zone
			(layer "F.Cu")
			(hatch none 0.5)
			(connect_pads
				(clearance 0)
			)
			(min_thickness 0.25)
			(keepout
				(tracks not_allowed)
				(vias allowed)
				(pads allowed)
				(copperpour not_allowed)
				(footprints allowed)
			)
			(placement
				(enabled no)
				(sheetname "")
			)
			(fill
				(thermal_gap 0.5)
				(thermal_bridge_width 0.5)
				(island_removal_mode 0)
			)
			(polygon
				(pts
					(xy 196.473826 -69.578474) (xy 196.473826 -69.070474) (xy 196.854826 -69.070474) (xy 196.854826 -69.578474)
				)
			)
		)
		(zone
			(layer "F.Cu")
			(hatch none 0.5)
			(connect_pads
				(clearance 0)
			)
			(min_thickness 0.25)
			(keepout
				(tracks allowed)
				(vias not_allowed)
				(pads allowed)
				(copperpour not_allowed)
				(footprints allowed)
			)
			(placement
				(enabled no)
				(sheetname "")
			)
			(fill
				(thermal_gap 0.5)
				(thermal_bridge_width 0.5)
				(island_removal_mode 0)
			)
			(polygon
				(pts
					(xy 196.854826 -69.578474) (xy 196.854826 -69.070474) (xy 196.473826 -69.070474) (xy 196.473826 -69.578474)
				)
			)
		)
	)
	(footprint ""
		(layer "F.Cu")
		(at 364.75924 -137.52957 -90)
		(property "Reference" "R7A17"
			(at 0 0 270)
			(layer "F.SilkS")
			(hide yes)
			(effects
				(font
					(size 1.27 1.27)
				)
			)
		)
		(property "Value" ""
			(at 0 0 270)
			(layer "F.Fab")
			(effects
				(font
					(size 1.27 1.27)
				)
			)
		)
		(duplicate_pad_numbers_are_jumpers no)
		(fp_rect
			(start 0.2794 0.9906)
			(end -0.2794 -0.1016)
			(stroke
				(width 0)
				(type default)
			)
			(fill no)
			(layer "F.CrtYd")
		)
		(fp_line
			(start -0.2794 0.9906)
			(end 0.2794 0.9906)
			(stroke
				(width 0.1)
				(type default)
			)
			(layer "F.Fab")
		)
		(fp_line
			(start 0.2794 0.9906)
			(end 0.2794 -0.1016)
			(stroke
				(width 0.1)
				(type default)
			)
			(layer "F.Fab")
		)
		(fp_line
			(start -0.2794 -0.1016)
			(end -0.2794 0.9906)
			(stroke
				(width 0.1)
				(type default)
			)
			(layer "F.Fab")
		)
		(fp_line
			(start 0.2794 -0.1016)
			(end -0.2794 -0.1016)
			(stroke
				(width 0.1)
				(type default)
			)
			(layer "F.Fab")
		)
		(pad "1" smd rect
			(at 0 0 270)
			(size 0.508 0.508)
			(layers "F.Cu" "F.Mask" "F.Paste")
			(net "SVID_CLK1_CPU0_R")
		)
		(pad "2" smd rect
			(at 0 0.889 270)
			(size 0.508 0.508)
			(layers "F.Cu" "F.Mask" "F.Paste")
			(net "SVID_CLK_PVDDQ_DEF")
		)
		(zone
			(layer "F.Cu")
			(hatch none 0.5)
			(connect_pads
				(clearance 0)
			)
			(min_thickness 0.25)
			(keepout
				(tracks allowed)
				(vias not_allowed)
				(pads allowed)
				(copperpour not_allowed)
				(footprints allowed)
			)
			(placement
				(enabled no)
				(sheetname "")
			)
			(fill
				(thermal_gap 0.5)
				(thermal_bridge_width 0.5)
				(island_removal_mode 0)
			)
			(polygon
				(pts
					(xy 364.12424 -137.27557) (xy 364.50524 -137.27557) (xy 364.50524 -137.78357) (xy 364.12424 -137.78357)
				)
			)
		)
		(zone
			(layer "F.Cu")
			(hatch none 0.5)
			(connect_pads
				(clearance 0)
			)
			(min_thickness 0.25)
			(keepout
				(tracks not_allowed)
				(vias allowed)
				(pads allowed)
				(copperpour not_allowed)
				(footprints allowed)
			)
			(placement
				(enabled no)
				(sheetname "")
			)
			(fill
				(thermal_gap 0.5)
				(thermal_bridge_width 0.5)
				(island_removal_mode 0)
			)
			(polygon
				(pts
					(xy 364.12424 -137.27557) (xy 364.50524 -137.27557) (xy 364.50524 -137.78357) (xy 364.12424 -137.78357)
				)
			)
		)
	)
)
